(kicad_pcb
	(version 20221018)
	(generator pcbnew)
	(general
    (thickness 1.518)
  )
	(paper "A4")
	(title_block
    (title "Kria K26 Devboard")
    (date "2024-03-26")
    (rev "1.2.5")
    (comment 1 "www.antmicro.com")
    (comment 2 "Antmicro Ltd.")
		(comment 9 "footprints 140-143 of 660")
	)
	(layers
    (0 "F.Cu" mixed)
    (1 "In1.Cu" power)
    (2 "In2.Cu" mixed)
    (3 "In3.Cu" power)
    (4 "In4.Cu" mixed)
    (5 "In5.Cu" power)
    (6 "In6.Cu" mixed)
    (31 "B.Cu" power)
    (32 "B.Adhes" user "B.Adhesive")
    (33 "F.Adhes" user "F.Adhesive")
    (34 "B.Paste" user)
    (35 "F.Paste" user)
    (36 "B.SilkS" user "B.Silkscreen")
    (37 "F.SilkS" user "F.Silkscreen")
    (38 "B.Mask" user)
    (39 "F.Mask" user)
    (40 "Dwgs.User" user "User.Drawings")
    (41 "Cmts.User" user "User.Comments")
    (42 "Eco1.User" user "User.Eco1")
    (43 "Eco2.User" user "User.Eco2")
    (44 "Edge.Cuts" user)
    (45 "Margin" user)
    (46 "B.CrtYd" user "B.Courtyard")
    (47 "F.CrtYd" user "F.Courtyard")
    (48 "B.Fab" user)
    (49 "F.Fab" user)
  )
	(footprint "kria-k26-devboard-footprints:LED_0603_1608Metric_G" (layer "F.Cu")
    (at 143.2 83.149999 90)
    (descr "LED SMD 0603 Green")
    (tags "LED SMD 0603 Green")
    (property "Author" "Antmicro")
    (property "Color" "Green")
    (property "License" "Apache-2.0")
    (property "MPN" "LG L29K-G2J1-24-Z")
    (property "Manufacturer" "OSRAM")
    (property "Sheetfile" "dc-dc-conventers.kicad_sch")
    (property "Sheetname" "DC/DC conventers")
    (property "ki_description" "LED, Green, SMT, 0603, 20 mA, 2.1 V, 570 nm")
    (property "ki_keywords" "0603, SMT, DIODE, SEMICONDUCTOR, UNICOLOR")
    (attr smd)
    (fp_text reference "D15" (at 1.559999 0.26 90) (layer "F.SilkS")
        (effects (font (size 0.7 0.7) (thickness 0.15)) (justify left bottom))
    )
    (fp_text value "LED_G_0603_LG_L29K-G2J1-24-Z" (at 0 1.6 90) (layer "F.Fab") hide
        (effects (font (size 0.7 0.7) (thickness 0.15)) (justify left bottom))
    )
    (fp_text user "License: Apache-2.0" (at -1.31 5.769 90) (layer "F.Fab") hide
        (effects (font (size 0.7 0.7) (thickness 0.15)) (justify left bottom))
    )
    (fp_text user "Author: Antmicro" (at -1.31 4.769 90) (layer "F.Fab") hide
        (effects (font (size 0.7 0.7) (thickness 0.15)) (justify left bottom))
    )
    (fp_text user "${REFERENCE}" (at -1.31 3.769 90) (layer "F.Fab") hide
        (effects (font (size 0.7 0.7) (thickness 0.15)) (justify left bottom))
    )
    (fp_line (start -0.27 -0.35) (end 0.27 -0.35)
      (stroke (width 0.15) (type solid)) (layer "F.SilkS"))
    (fp_line (start -0.27 0.351) (end 0.27 0.351)
      (stroke (width 0.15) (type solid)) (layer "F.SilkS"))
    (fp_line (start -0.106328 -0.200008) (end -0.106328 0.199992)
      (stroke (width 0.1) (type solid)) (layer "F.SilkS"))
    (fp_line (start -0.106328 -0.200008) (end 0.093672 -0.000008)
      (stroke (width 0.1) (type solid)) (layer "F.SilkS"))
    (fp_line (start -0.106328 -0.000008) (end -0.29 0)
      (stroke (width 0.1) (type solid)) (layer "F.SilkS"))
    (fp_line (start 0.093672 -0.200008) (end 0.093672 0.199992)
      (stroke (width 0.1) (type solid)) (layer "F.SilkS"))
    (fp_line (start 0.093672 -0.000008) (end -0.106328 0.199992)
      (stroke (width 0.1) (type solid)) (layer "F.SilkS"))
    (fp_line (start 0.093672 -0.000008) (end 0.293672 -0.000008)
      (stroke (width 0.1) (type solid)) (layer "F.SilkS"))
    (fp_line (start 1.25 0.32) (end 1.25 -0.32)
      (stroke (width 0.15) (type solid)) (layer "F.SilkS"))
    (fp_rect (start 1.26 0.65) (end -1.26 -0.65)
      (stroke (width 0.05) (type solid)) (fill none) (layer "F.CrtYd"))
    (fp_line (start -0.599 0) (end -0.201 0)
      (stroke (width 0.15) (type solid)) (layer "F.Fab"))
    (fp_line (start -0.201 -0.2) (end -0.201 0)
      (stroke (width 0.15) (type solid)) (layer "F.Fab"))
    (fp_line (start -0.201 0) (end -0.201 0.202)
      (stroke (width 0.15) (type solid)) (layer "F.Fab"))
    (fp_line (start -0.201 0.202) (end 0.101 0)
      (stroke (width 0.15) (type solid)) (layer "F.Fab"))
    (fp_line (start 0.101 0) (end -0.201 -0.2)
      (stroke (width 0.15) (type solid)) (layer "F.Fab"))
    (fp_line (start 0.199 -0.2) (end 0.199 -0.1)
      (stroke (width 0.15) (type solid)) (layer "F.Fab"))
    (fp_line (start 0.199 0) (end 0.597 0)
      (stroke (width 0.15) (type solid)) (layer "F.Fab"))
    (fp_line (start 0.199 0.202) (end 0.199 -0.1)
      (stroke (width 0.15) (type solid)) (layer "F.Fab"))
    (fp_rect (start -0.848 -0.4) (end 0.85 0.402)
      (stroke (width 0.15) (type solid)) (fill none) (layer "F.Fab"))
    (pad "1" smd rect (at -0.75 0 270) (size 0.8 0.8) (layers "F.Cu" "F.Paste" "F.Mask")
      (net 240 "Net-(D15-Pad1)") (pintype "passive"))
    (pad "2" smd rect (at 0.75 0 270) (size 0.8 0.8) (layers "F.Cu" "F.Paste" "F.Mask")
      (net 1 "GND") (pinfunction "2") (pintype "passive"))
  )
	(footprint "kria-k26-devboard-footprints:DFN1210-6" (layer "F.Cu")
    (at 92.1 68.5 -90)
    (property "Author" "Antmicro")
    (property "License" "Apache-2.0")
    (property "MPN" "824012823")
    (property "Manufacturer" "Würth Elektronik")
    (property "Sheetfile" "dp.kicad_sch")
    (property "Sheetname" "Display Port")
    (property "ki_description" "Low Capacitance TVS Diode Array, 2 Channels, DFN1210-6L")
    (property "ki_keywords" "ESD Protection TVS USB 3.1 Gen1&2 (5Gb/s, 10Gb/s), USB 3.1 Type C, Display Port (1.1, 1.2, 1.3, 1.4), HDMI 2.0")
    (attr smd)
    (fp_text reference "U4" (at 1.25 0.78) (layer "F.SilkS")
        (effects (font (size 0.697684 0.697684) (thickness 0.15)) (justify left))
    )
    (fp_text value "824012823" (at 6.127 1.4 -90) (layer "F.Fab")
        (effects (font (size 0.7 0.7) (thickness 0.15)) (justify left bottom))
    )
    (fp_text user "License: Apache-2.0" (at -1.01 5.4 -90) (layer "F.Fab") hide
        (effects (font (size 0.7 0.7) (thickness 0.15)) (justify left bottom))
    )
    (fp_text user "Author: Antmicro" (at -1.01 4.4 -90) (layer "F.Fab") hide
        (effects (font (size 0.7 0.7) (thickness 0.15)) (justify left bottom))
    )
    (fp_text user "${REFERENCE}" (at -1.01 3.399 -90) (layer "F.Fab") hide
        (effects (font (size 0.7 0.7) (thickness 0.15)) (justify left bottom))
    )
    (fp_line (start -0.532 -0.63) (end 0.53 -0.63)
      (stroke (width 0.15) (type solid)) (layer "F.SilkS"))
    (fp_line (start -0.532 0.628) (end 0.53 0.628)
      (stroke (width 0.15) (type solid)) (layer "F.SilkS"))
    (fp_circle (center -1.31 -0.36) (end -1.25 -0.31)
      (stroke (width 0.15) (type solid)) (fill solid) (layer "F.SilkS"))
    (fp_rect (start -0.75 -0.85) (end 0.748 0.848)
      (stroke (width 0.05) (type solid)) (fill none) (layer "F.CrtYd"))
    (fp_line (start -0.532 -0.532) (end 0.53 -0.532)
      (stroke (width 0.15) (type solid)) (layer "F.Fab"))
    (fp_line (start -0.532 0.53) (end -0.532 -0.532)
      (stroke (width 0.15) (type solid)) (layer "F.Fab"))
    (fp_line (start 0.53 -0.532) (end 0.53 0.53)
      (stroke (width 0.15) (type solid)) (layer "F.Fab"))
    (fp_line (start 0.53 0.53) (end -0.532 0.53)
      (stroke (width 0.15) (type solid)) (layer "F.Fab"))
    (pad "1" smd roundrect (at -0.277 -0.351 270) (size 0.4 0.2) (layers "F.Cu" "F.Paste" "F.Mask") (roundrect_rratio 0.25)
      (net 363 "/Display Port/DP_AUX_C_TVS_N") (pintype "passive"))
    (pad "2" smd roundrect (at -0.277 0 270) (size 0.4 0.2) (layers "F.Cu" "F.Paste" "F.Mask") (roundrect_rratio 0.25)
      (net 362 "/Display Port/DP_AUX_C_TVS_P") (pintype "passive"))
    (pad "3" smd roundrect (at -0.277 0.349 270) (size 0.4 0.2) (layers "F.Cu" "F.Paste" "F.Mask") (roundrect_rratio 0.25)
      (net 1 "GND") (pintype "passive"))
    (pad "4" smd roundrect (at 0.275 0.349 270) (size 0.4 0.2) (layers "F.Cu" "F.Paste" "F.Mask") (roundrect_rratio 0.25)
      (net 1 "GND") (pintype "passive"))
    (pad "5" smd roundrect (at 0.275 0 270) (size 0.4 0.2) (layers "F.Cu" "F.Paste" "F.Mask") (roundrect_rratio 0.25)
      (net 97 "/Display Port/DP_AUX_C_P") (pintype "passive"))
    (pad "6" smd roundrect (at 0.275 -0.351 270) (size 0.4 0.2) (layers "F.Cu" "F.Paste" "F.Mask") (roundrect_rratio 0.25)
      (net 99 "/Display Port/DP_AUX_C_N") (pintype "passive"))
  )
	(footprint "kria-k26-devboard-footprints:MicroSD_Amphenol_1140084168" (layer "F.Cu")
    (at 130.9 145.3)
    (property "Author" "Antmicro")
    (property "License" "Apache-2.0")
    (property "MPN" "1140084168")
    (property "Manufacturer" "Amphenol")
    (property "Sheetfile" "sd-3-card.kicad_sch")
    (property "Sheetname" "SD 3.0 card")
    (property "ki_description" "Memory Card Connector, MicroSD, Push-Pull, 8 Contacts, Copper Alloy, Gold Plated Contacts")
    (property "ki_keywords" "HORIZONTAL, SMT, MEMORY, CONNECTOR, MICRO")
    (attr smd)
    (fp_text reference "J2" (at -6.26 -5) (layer "F.SilkS")
        (effects (font (size 0.7 0.7) (thickness 0.15)) (justify left bottom))
    )
    (fp_text value "MicroSD_1140084168" (at -6.9 11.4) (layer "F.Fab") hide
        (effects (font (size 0.7 0.7) (thickness 0.15)) (justify left bottom))
    )
    (fp_text user "Author: Antmicro" (at -6.925 14.1) (layer "F.Fab") hide
        (effects (font (size 0.7 0.7) (thickness 0.15)) (justify left bottom))
    )
    (fp_text user "${REFERENCE}" (at -6.925 12.774) (layer "F.Fab") hide
        (effects (font (size 0.7 0.7) (thickness 0.15)) (justify left bottom))
    )
    (fp_text user "License: Apache-2.0" (at -6.925 15.4) (layer "F.Fab") hide
        (effects (font (size 0.7 0.7) (thickness 0.15)) (justify left bottom))
    )
    (fp_line (start -6.3 -6.1) (end -6.3 -4.7)
      (stroke (width 0.15) (type solid)) (layer "F.SilkS"))
    (fp_line (start -6.3 -1.6) (end -6.3 4.2)
      (stroke (width 0.15) (type solid)) (layer "F.SilkS"))
    (fp_line (start 4.8 -6.1) (end -6.3 -6.1)
      (stroke (width 0.15) (type solid)) (layer "F.SilkS"))
    (fp_line (start 6.2 -6.1) (end 6.1 -6.1)
      (stroke (width 0.15) (type solid)) (layer "F.SilkS"))
    (fp_line (start 6.2 -4) (end 6.2 -6.1)
      (stroke (width 0.15) (type solid)) (layer "F.SilkS"))
    (fp_line (start 6.2 4.2) (end 6.2 -2.2)
      (stroke (width 0.15) (type solid)) (layer "F.SilkS"))
    (fp_rect (start -6.5 -6.3) (end 6.4 6.2)
      (stroke (width 0.05) (type solid)) (fill none) (layer "F.CrtYd"))
    (fp_line (start -5.6 5.8) (end -5.6 9.5)
      (stroke (width 0.12) (type solid)) (layer "F.Fab"))
    (fp_line (start -5.1 8.8) (end -5.6 8.9)
      (stroke (width 0.12) (type solid)) (layer "F.Fab"))
    (fp_line (start -5.1 9.1) (end -5.6 9.2)
      (stroke (width 0.12) (type solid)) (layer "F.Fab"))
    (fp_line (start -3.8 8.5) (end -5.1 8.8)
      (stroke (width 0.12) (type solid)) (layer "F.Fab"))
    (fp_line (start -3.8 8.8) (end -5.1 9.1)
      (stroke (width 0.12) (type solid)) (layer "F.Fab"))
    (fp_line (start -2.3 8.3) (end -3.8 8.5)
      (stroke (width 0.12) (type solid)) (layer "F.Fab"))
    (fp_line (start -2.3 8.6) (end -3.8 8.8)
      (stroke (width 0.12) (type solid)) (layer "F.Fab"))
    (fp_line (start -1 8.2) (end -2.3 8.3)
      (stroke (width 0.12) (type solid)) (layer "F.Fab"))
    (fp_line (start -1 8.5) (end -2.3 8.6)
      (stroke (width 0.12) (type solid)) (layer "F.Fab"))
    (fp_line (start 0.8 8.2) (end -1 8.2)
      (stroke (width 0.12) (type solid)) (layer "F.Fab"))
    (fp_line (start 0.8 8.5) (end -1 8.5)
      (stroke (width 0.12) (type solid)) (layer "F.Fab"))
    (fp_line (start 2.1 8.3) (end 0.8 8.2)
      (stroke (width 0.12) (type solid)) (layer "F.Fab"))
    (fp_line (start 2.1 8.6) (end 0.8 8.5)
      (stroke (width 0.12) (type solid)) (layer "F.Fab"))
    (fp_line (start 2.9 8.4) (end 2.1 8.3)
      (stroke (width 0.12) (type solid)) (layer "F.Fab"))
    (fp_line (start 2.9 8.7) (end 2.1 8.6)
      (stroke (width 0.12) (type solid)) (layer "F.Fab"))
    (fp_line (start 4.6 8.7) (end 2.9 8.4)
      (stroke (width 0.12) (type solid)) (layer "F.Fab"))
    (fp_line (start 4.6 9) (end 2.9 8.7)
      (stroke (width 0.12) (type solid)) (layer "F.Fab"))
    (fp_line (start 4.9 10) (end -5.1 10)
      (stroke (width 0.12) (type solid)) (layer "F.Fab"))
    (fp_line (start 5.4 8.9) (end 4.6 8.7)
      (stroke (width 0.12) (type solid)) (layer "F.Fab"))
    (fp_line (start 5.4 9.2) (end 4.6 9)
      (stroke (width 0.12) (type solid)) (layer "F.Fab"))
    (fp_line (start 5.4 9.5) (end 5.4 5.8)
      (stroke (width 0.12) (type solid)) (layer "F.Fab"))
    (fp_rect (start -6 -5.8) (end 5.999 5.799)
      (stroke (width 0.1) (type solid)) (fill none) (layer "F.Fab"))
    (fp_arc (start -5.1 10) (mid -5.453553 9.853553) (end -5.6 9.5)
      (stroke (width 0.12) (type solid)) (layer "F.Fab"))
    (fp_arc (start 5.4 9.5) (mid 5.253553 9.853553) (end 4.9 10)
      (stroke (width 0.12) (type solid)) (layer "F.Fab"))
    (pad "1" smd rect (at 3.124 5.254 180) (size 0.7 1.75) (layers "F.Cu" "F.Paste" "F.Mask")
      (net 264 "/SD 3.0 card/SD_DAT2") (pinfunction "DAT2") (pintype "bidirectional"))
    (pad "2" smd rect (at 2.024 5.254 180) (size 0.7 1.75) (layers "F.Cu" "F.Paste" "F.Mask")
      (net 263 "/SD 3.0 card/SD_DAT3") (pinfunction "CD/DAT3") (pintype "bidirectional"))
    (pad "3" smd rect (at 0.925 5.254 180) (size 0.7 1.75) (layers "F.Cu" "F.Paste" "F.Mask")
      (net 262 "/SD 3.0 card/SD_CMD") (pinfunction "CMD") (pintype "bidirectional"))
    (pad "4" smd rect (at -0.176 5.254 180) (size 0.7 1.75) (layers "F.Cu" "F.Paste" "F.Mask")
      (net 317 "/SD 3.0 card/SD_VDD") (pinfunction "VDD") (pintype "power_in"))
    (pad "5" smd rect (at -1.276 5.254 180) (size 0.7 1.75) (layers "F.Cu" "F.Paste" "F.Mask")
      (net 261 "/SD 3.0 card/SD_CLK") (pinfunction "CLK") (pintype "output"))
    (pad "6" smd rect (at -2.375 5.254 180) (size 0.7 1.75) (layers "F.Cu" "F.Paste" "F.Mask")
      (net 1 "GND") (pinfunction "VSS") (pintype "power_in"))
    (pad "7" smd rect (at -3.476 5.254 180) (size 0.7 1.75) (layers "F.Cu" "F.Paste" "F.Mask")
      (net 260 "/SD 3.0 card/SD_DAT0") (pinfunction "DAT0") (pintype "bidirectional"))
    (pad "8" smd rect (at -4.576 5.254 180) (size 0.7 1.75) (layers "F.Cu" "F.Paste" "F.Mask")
      (net 259 "/SD 3.0 card/SD_DAT1") (pinfunction "DAT1") (pintype "bidirectional"))
    (pad "9" smd rect (at -5.675 -4.05) (size 1.4 1) (layers "F.Cu" "F.Paste" "F.Mask")
      (net 106 "/SD 3.0 card/MIO45") (pinfunction "CD1") (pintype "passive"))
    (pad "10" smd rect (at 5.424 -5.531 90) (size 1.4 1) (layers "F.Cu" "F.Paste" "F.Mask")
      (net 1 "GND") (pinfunction "CD2") (pintype "passive"))
    (pad "SH" smd rect (at -5.976 -2.48 90) (size 1.5 0.8) (layers "F.Cu" "F.Paste" "F.Mask")
      (net 1 "GND") (pinfunction "Shell") (pintype "passive"))
    (pad "SH" smd rect (at -5.776 5.129) (size 1.3 1.5) (layers "F.Cu" "F.Paste" "F.Mask")
      (net 1 "GND") (pinfunction "Shell") (pintype "passive"))
    (pad "SH" smd rect (at 5.575 5.129) (size 1.5 1.5) (layers "F.Cu" "F.Paste" "F.Mask")
      (net 1 "GND") (pinfunction "Shell") (pintype "passive"))
    (pad "SH" smd rect (at 5.874 -3.13 90) (size 1.5 0.8) (layers "F.Cu" "F.Paste" "F.Mask")
      (net 1 "GND") (pinfunction "Shell") (pintype "passive"))
  )
	(footprint "kria-k26-devboard-footprints:SOT-563" (layer "F.Cu")
    (at 144.49 61.9 90)
    (property "Author" "Antmicro")
    (property "License" "Apache-2.0")
    (property "MPN" "82400152")
    (property "Manufacturer" "Würth Elektronik")
    (property "Sheetfile" "usbc-socket.kicad_sch")
    (property "Sheetname" "USB-C socket")
    (property "ki_description" "TVS diode")
    (property "ki_keywords" "SMT, DIODE, IC, ESD, TVS")
    (attr smd)
    (fp_text reference "U59" (at -1.93 -1.26 180) (layer "F.SilkS")
        (effects (font (size 0.7 0.7) (thickness 0.15)) (justify left bottom))
    )
    (fp_text value "82400152" (at 0 2 90) (layer "F.Fab") hide
        (effects (font (size 0.7 0.7) (thickness 0.15)) (justify left bottom))
    )
    (fp_text user "${REFERENCE}" (at -1.299 7.323 90) (layer "F.Fab") hide
        (effects (font (size 0.7 0.7) (thickness 0.15)) (justify left bottom))
    )
    (fp_text user "Author: Antmicro" (at -1.299 6.124 90) (layer "F.Fab") hide
        (effects (font (size 0.7 0.7) (thickness 0.15)) (justify left bottom))
    )
    (fp_text user "License: Apache-2.0" (at -1.299 4.924 90) (layer "F.Fab") hide
        (effects (font (size 0.7 0.7) (thickness 0.15)) (justify left bottom))
    )
    (fp_line (start -0.778 0.776) (end -0.778 0.949)
      (stroke (width 0.15) (type solid)) (layer "F.SilkS"))
    (fp_line (start -0.778 0.949) (end -0.424 0.949)
      (stroke (width 0.15) (type solid)) (layer "F.SilkS"))
    (fp_line (start -0.499 -0.974) (end -0.724 -0.778)
      (stroke (width 0.15) (type solid)) (layer "F.SilkS"))
    (fp_line (start 0.776 -0.974) (end 0.526 -0.974)
      (stroke (width 0.15) (type solid)) (layer "F.SilkS"))
    (fp_line (start 0.776 -0.974) (end 0.776 -0.778)
      (stroke (width 0.15) (type solid)) (layer "F.SilkS"))
    (fp_line (start 0.776 0.776) (end 0.776 0.972)
      (stroke (width 0.15) (type solid)) (layer "F.SilkS"))
    (fp_line (start 0.776 0.972) (end 0.526 0.972)
      (stroke (width 0.15) (type solid)) (layer "F.SilkS"))
    (fp_circle (center -0.903 -0.999) (end -0.952 -0.95)
      (stroke (width 0.15) (type solid)) (fill solid) (layer "F.SilkS"))
    (fp_rect (start 1.19 -1.12) (end -1.2 1.1)
      (stroke (width 0.05) (type solid)) (fill none) (layer "F.CrtYd"))
    (fp_line (start -0.653 -0.678) (end -0.653 0.847)
      (stroke (width 0.15) (type solid)) (layer "F.Fab"))
    (fp_line (start -0.453 -0.849) (end -0.653 -0.678)
      (stroke (width 0.15) (type solid)) (layer "F.Fab"))
    (fp_line (start -0.453 -0.849) (end 0.651 -0.849)
      (stroke (width 0.15) (type solid)) (layer "F.Fab"))
    (fp_line (start 0.651 -0.849) (end 0.651 0.847)
      (stroke (width 0.15) (type solid)) (layer "F.Fab"))
    (fp_line (start 0.651 0.847) (end -0.653 0.847)
      (stroke (width 0.15) (type solid)) (layer "F.Fab"))
    (pad "1" smd roundrect (at -0.749 -0.499) (size 0.3 0.6) (layers "F.Cu" "F.Paste" "F.Mask") (roundrect_rratio 0.25)
      (net 308 "/Debug and JTAG/USBC_CC2") (pintype "passive"))
    (pad "2" smd roundrect (at -0.749 0.001) (size 0.3 0.6) (layers "F.Cu" "F.Paste" "F.Mask") (roundrect_rratio 0.25)
      (net 1 "GND") (pintype "passive"))
    (pad "3" smd roundrect (at -0.749 0.497) (size 0.3 0.6) (layers "F.Cu" "F.Paste" "F.Mask") (roundrect_rratio 0.25)
      (net 307 "/Debug and JTAG/USBC_CC1") (pintype "passive"))
    (pad "4" smd roundrect (at 0.747 0.497) (size 0.3 0.6) (layers "F.Cu" "F.Paste" "F.Mask") (roundrect_rratio 0.25)
      (net 301 "/Power Supply/USB-C socket/USBC_TVS_CC1") (pintype "passive"))
    (pad "5" smd roundrect (at 0.747 0.001) (size 0.3 0.6) (layers "F.Cu" "F.Paste" "F.Mask") (roundrect_rratio 0.25)
      (net 756 "unconnected-(U59-Pad5)") (pintype "passive+no_connect"))
    (pad "6" smd roundrect (at 0.747 -0.499) (size 0.3 0.6) (layers "F.Cu" "F.Paste" "F.Mask") (roundrect_rratio 0.25)
      (net 300 "/Power Supply/USB-C socket/USBC_TVS_CC2") (pintype "passive"))
  )
)
